# BASEBOARD_FAB2 (Tioga Pass) — schematic netlist excerpt (pin names and nets, part order shuffled) for the footprints in the layout excerpt that follows; sources: Cadence DE-HDL packaged netlist, KiCad conversion of Wiwynn_Tioga_Pass_MB.brd

C25W82  CAP  10.0PF 50V 5% COG  pkg 0402LF  page 252 : A = V_IO_VSYNC_J ; B = GND
R4F2  RES  0.002 1% CHIP  pkg 1206  page 197 : A = P12V_STBY ; B = P12V_NVDIMM_ABC
R25W26  120R2F-GP  1%  pkg RCL_GP  page 151 : \1\ = GND ; \2\ = BMC_M_MACT_N

(kicad_pcb
	(version 20260206)
	(generator "pcbnew")
	(generator_version "10.0")
	(general
		(thickness 1.6)
		(legacy_teardrops no)
	)
	(paper "A4")
	(title_block
		(title "Wiwynn_Tioga_Pass_MB.brd")
		(comment 1 "Tioga Pass / footprints 898-900 of 4770")
	)
	(layers
		(0 "F.Cu" signal "TOP")
		(4 "In1.Cu" signal "L2GND")
		(6 "In2.Cu" signal "L3")
		(8 "In3.Cu" signal "L4GND")
		(10 "In4.Cu" signal "L5")
		(12 "In5.Cu" signal "L6GND")
		(14 "In6.Cu" signal "L7VCC")
		(16 "In7.Cu" signal "L8VCC")
		(18 "In8.Cu" signal "L9GND")
		(20 "In9.Cu" signal "L10")
		(22 "In10.Cu" signal "L11GND")
		(24 "In11.Cu" signal "L12")
		(26 "In12.Cu" signal "L13GND")
		(2 "B.Cu" signal "BOTTOM")
		(9 "F.Adhes" user "F.Adhesive")
		(11 "B.Adhes" user "B.Adhesive")
		(13 "F.Paste" user "Package Geometry/Pastemask Top")
		(15 "B.Paste" user "Package Geometry/Pastemask Bottom")
		(5 "F.SilkS" user "Ref Des/Silkscreen Top")
		(7 "B.SilkS" user "Ref Des/Silkscreen Bottom")
		(1 "F.Mask" user "Board Geometry/Soldermask Top")
		(3 "B.Mask" user "Board Geometry/Soldermask Bottom")
		(17 "Dwgs.User" user "User.Drawings")
		(19 "Cmts.User" user "User.Comments")
		(21 "Eco1.User" user "User.Eco1")
		(23 "Eco2.User" user "User.Eco2")
		(25 "Edge.Cuts" user "Board Geometry/Outline")
		(27 "Margin" user)
		(31 "F.CrtYd" user "Package Geometry/Place Bound Top")
		(29 "B.CrtYd" user "Package Geometry/Place Bound Bottom")
		(35 "F.Fab" user "Ref Des/Assembly Top")
		(33 "B.Fab" user "Ref Des/Assembly Bottom")
	)
	(footprint ""
		(layer "F.Cu")
		(at 493.168686 -46.569884 180)
		(property "Reference" "C25W82"
			(at -0.8382 -0.67818 180)
			(unlocked yes)
			(layer "F.SilkS")
			(effects
				(font
					(size 0.4064 0.254)
					(thickness 0.1524)
				)
				(justify left)
			)
		)
		(property "Value" ""
			(at 0 0 180)
			(layer "F.Fab")
			(effects
				(font
					(size 1.27 1.27)
				)
			)
		)
		(duplicate_pad_numbers_are_jumpers no)
		(fp_poly
			(pts
				(xy 0.3048 -0.1016) (xy 0.3048 0.9906) (xy -0.3048 0.9906) (xy -0.3048 -0.1016)
			)
			(stroke
				(width 0)
				(type default)
			)
			(fill no)
			(layer "F.CrtYd")
		)
		(fp_line
			(start 0.3048 0.9906)
			(end 0.3048 -0.1016)
			(stroke
				(width 0.1)
				(type default)
			)
			(layer "F.Fab")
		)
		(fp_line
			(start 0.3048 -0.1016)
			(end -0.3048 -0.1016)
			(stroke
				(width 0.1)
				(type default)
			)
			(layer "F.Fab")
		)
		(fp_line
			(start -0.3048 0.9906)
			(end 0.3048 0.9906)
			(stroke
				(width 0.1)
				(type default)
			)
			(layer "F.Fab")
		)
		(fp_line
			(start -0.3048 -0.1016)
			(end -0.3048 0.9906)
			(stroke
				(width 0.1)
				(type default)
			)
			(layer "F.Fab")
		)
		(pad "1" smd rect
			(at 0 0 180)
			(size 0.508 0.508)
			(layers "F.Cu" "F.Mask" "F.Paste")
			(net "V_IO_VSYNC_J")
		)
		(pad "2" smd rect
			(at 0 0.889 180)
			(size 0.508 0.508)
			(layers "F.Cu" "F.Mask" "F.Paste")
			(net "GND")
		)
		(zone
			(layer "F.Cu")
			(hatch none 0.5)
			(connect_pads
				(clearance 0)
			)
			(min_thickness 0.25)
			(keepout
				(tracks not_allowed)
				(vias allowed)
				(pads allowed)
				(copperpour not_allowed)
				(footprints allowed)
			)
			(placement
				(enabled no)
				(sheetname "")
			)
			(fill
				(thermal_gap 0.5)
				(thermal_bridge_width 0.5)
				(island_removal_mode 0)
			)
			(polygon
				(pts
					(xy 493.422686 -47.204884) (xy 492.914686 -47.204884) (xy 492.914686 -46.823884) (xy 493.422686 -46.823884)
				)
			)
		)
		(zone
			(layer "F.Cu")
			(hatch none 0.5)
			(connect_pads
				(clearance 0)
			)
			(min_thickness 0.25)
			(keepout
				(tracks allowed)
				(vias not_allowed)
				(pads allowed)
				(copperpour not_allowed)
				(footprints allowed)
			)
			(placement
				(enabled no)
				(sheetname "")
			)
			(fill
				(thermal_gap 0.5)
				(thermal_bridge_width 0.5)
				(island_removal_mode 0)
			)
			(polygon
				(pts
					(xy 493.422686 -46.823884) (xy 492.914686 -46.823884) (xy 492.914686 -47.204884) (xy 493.422686 -47.204884)
				)
			)
		)
	)
	(footprint ""
		(layer "F.Cu")
		(at 184.785 -26.416)
		(property "Reference" "R4F2"
			(at 0 0 0)
			(layer "F.SilkS")
			(hide yes)
			(effects
				(font
					(size 1.27 1.27)
				)
			)
		)
		(property "Value" ""
			(at 0 0 0)
			(layer "F.Fab")
			(effects
				(font
					(size 1.27 1.27)
				)
			)
		)
		(duplicate_pad_numbers_are_jumpers no)
		(fp_line
			(start -0.9017 1.951736)
			(end -0.9017 0.823468)
			(stroke
				(width 0.1524)
				(type default)
			)
			(layer "F.SilkS")
		)
		(fp_line
			(start 0.9017 1.952498)
			(end 0.9017 0.853948)
			(stroke
				(width 0.1524)
				(type default)
			)
			(layer "F.SilkS")
		)
		(fp_poly
			(pts
				(xy -0.9017 3.0988) (xy 0.9017 3.0988) (xy 0.9017 -0.3048) (xy -0.9017 -0.3048)
			)
			(stroke
				(width 0)
				(type default)
			)
			(fill no)
			(layer "F.CrtYd")
		)
		(fp_line
			(start -0.9017 -0.3048)
			(end -0.9017 3.0988)
			(stroke
				(width 0.1)
				(type default)
			)
			(layer "F.Fab")
		)
		(fp_line
			(start -0.9017 3.0988)
			(end 0.9017 3.0988)
			(stroke
				(width 0.1)
				(type default)
			)
			(layer "F.Fab")
		)
		(fp_line
			(start 0.9017 -0.3048)
			(end -0.9017 -0.3048)
			(stroke
				(width 0.1)
				(type default)
			)
			(layer "F.Fab")
		)
		(fp_line
			(start 0.9017 3.0988)
			(end 0.9017 -0.3048)
			(stroke
				(width 0.1)
				(type default)
			)
			(layer "F.Fab")
		)
		(pad "1" smd rect
			(at 0 0)
			(size 1.524 1.016)
			(layers "F.Cu" "F.Mask" "F.Paste")
			(net "P12V_STBY")
		)
		(pad "2" smd rect
			(at 0 2.794)
			(size 1.524 1.016)
			(layers "F.Cu" "F.Mask" "F.Paste")
			(net "P12V_NVDIMM_ABC")
		)
		(zone
			(layer "F.Cu")
			(hatch none 0.5)
			(connect_pads
				(clearance 0)
			)
			(min_thickness 0.25)
			(keepout
				(tracks allowed)
				(vias not_allowed)
				(pads allowed)
				(copperpour not_allowed)
				(footprints allowed)
			)
			(placement
				(enabled no)
				(sheetname "")
			)
			(fill
				(thermal_gap 0.5)
				(thermal_bridge_width 0.5)
				(island_removal_mode 0)
			)
			(polygon
				(pts
					(xy 184.023 -24.13) (xy 185.547 -24.13) (xy 185.547 -25.908) (xy 184.023 -25.908)
				)
			)
		)
	)
	(footprint ""
		(layer "F.Cu")
		(at 449.69938 -32.4485 90)
		(property "Reference" "R25W26"
			(at 0 0 90)
			(layer "F.SilkS")
			(hide yes)
			(effects
				(font
					(size 1.27 1.27)
				)
			)
		)
		(property "Value" "*"
			(at 0.064008 -4.108196 90)
			(unlocked yes)
			(layer "F.Fab")
			(hide yes)
			(effects
				(font
					(size 1.27 1.016)
					(thickness 0.1524)
				)
			)
		)
		(property "Device Type" "120R2F-GP_RCL_GP-120R2F-GP,64.A"
			(at 0.064008 -5.632196 90)
			(unlocked yes)
			(layer "F.Fab")
			(hide yes)
			(effects
				(font
					(size 1.27 1.016)
					(thickness 0.1524)
				)
			)
		)
		(duplicate_pad_numbers_are_jumpers no)
		(fp_line
			(start 0.508 -0.9398)
			(end -0.508 -0.9398)
			(stroke
				(width 0.1524)
				(type default)
			)
			(layer "F.SilkS")
		)
		(fp_line
			(start -0.508 -0.9398)
			(end -0.508 0.9398)
			(stroke
				(width 0.1524)
				(type default)
			)
			(layer "F.SilkS")
		)
		(fp_rect
			(start -0.508 0.9398)
			(end 0.508 -0.9398)
			(stroke
				(width 0)
				(type default)
			)
			(fill no)
			(layer "F.CrtYd")
		)
		(fp_rect
			(start -0.508 0.9398)
			(end 0.508 -0.9398)
			(stroke
				(width 0)
				(type default)
			)
			(fill no)
			(layer "F.Fab")
		)
		(pad "1" smd custom
			(at 0 -0.4445 90)
			(size 0.1397 0.1397)
			(layers "F.Cu" "F.Mask" "F.Paste")
			(net "GND")
			(options
				(clearance outline)
				(anchor circle)
			)
			(primitives
				(gr_poly
					(pts
						(arc
							(start -0.1778 -0.2794)
							(mid -0.249642 -0.249642)
							(end -0.2794 -0.1778)
						)
						(arc
							(start -0.2794 0.1778)
							(mid -0.249642 0.249642)
							(end -0.1778 0.2794)
						)
						(arc
							(start 0.1778 0.2794)
							(mid 0.249642 0.249642)
							(end 0.2794 0.1778)
						)
						(arc
							(start 0.2794 -0.1778)
							(mid 0.249642 -0.249642)
							(end 0.1778 -0.2794)
						)
					)
					(width 0)
					(fill yes)
				)
			)
		)
		(pad "2" smd custom
			(at 0 0.4445 90)
			(size 0.1397 0.1397)
			(layers "F.Cu" "F.Mask" "F.Paste")
			(net "BMC_M_MACT_N")
			(options
				(clearance outline)
				(anchor circle)
			)
			(primitives
				(gr_poly
					(pts
						(arc
							(start -0.1778 -0.2794)
							(mid -0.249642 -0.249642)
							(end -0.2794 -0.1778)
						)
						(arc
							(start -0.2794 0.1778)
							(mid -0.249642 0.249642)
							(end -0.1778 0.2794)
						)
						(arc
							(start 0.1778 0.2794)
							(mid 0.249642 0.249642)
							(end 0.2794 0.1778)
						)
						(arc
							(start 0.2794 -0.1778)
							(mid 0.249642 -0.249642)
							(end 0.1778 -0.2794)
						)
					)
					(width 0)
					(fill yes)
				)
			)
		)
	)
)
